(kicad_pcb
	(version 20260206)
	(generator "pcbnew")
	(generator_version "10.0")
	(general
		(thickness 1.6)
		(legacy_teardrops no)
	)
	(paper "A4")
	(title_block
		(title "04192023_DAF0TMB3IC0_F0TG_MB_C_brd_V02_OCP.brd")
		(comment 1 "Grand Teton / footprints 6220-6225 of 8354")
	)
	(layers
		(0 "F.Cu" signal "TOP")
		(4 "In1.Cu" signal "GND")
		(6 "In2.Cu" signal "IN1")
		(8 "In3.Cu" signal "GND1")
		(10 "In4.Cu" signal "IN2")
		(12 "In5.Cu" signal "GND2")
		(14 "In6.Cu" signal "IN3")
		(16 "In7.Cu" signal "GND3")
		(18 "In8.Cu" signal "VCC")
		(20 "In9.Cu" signal "VCC1")
		(22 "In10.Cu" signal "GND4")
		(24 "In11.Cu" signal "IN4")
		(26 "In12.Cu" signal "GND5")
		(28 "In13.Cu" signal "IN5")
		(30 "In14.Cu" signal "GND6")
		(32 "In15.Cu" signal "IN6")
		(34 "In16.Cu" signal "GND7")
		(2 "B.Cu" signal "BOTTOM")
		(9 "F.Adhes" user "F.Adhesive")
		(11 "B.Adhes" user "B.Adhesive")
		(13 "F.Paste" user "Package Geometry/Pastemask Top")
		(15 "B.Paste" user "Package Geometry/Pastemask Bottom")
		(5 "F.SilkS" user "Ref Des/Silkscreen Top")
		(7 "B.SilkS" user "Ref Des/Silkscreen Bottom")
		(1 "F.Mask" user "Board Geometry/Soldermask Top")
		(3 "B.Mask" user "Board Geometry/Soldermask Bottom")
		(17 "Dwgs.User" user "User.Drawings")
		(19 "Cmts.User" user "User.Comments")
		(21 "Eco1.User" user "User.Eco1")
		(23 "Eco2.User" user "User.Eco2")
		(25 "Edge.Cuts" user "Board Geometry/Outline")
		(27 "Margin" user)
		(31 "F.CrtYd" user "Package Geometry/Place Bound Top")
		(29 "B.CrtYd" user "Package Geometry/Place Bound Bottom")
		(35 "F.Fab" user "Ref Des/Assembly Top")
		(33 "B.Fab" user "Ref Des/Assembly Bottom")
	)
	(footprint ""
		(layer "B.Cu")
		(at 97.919032 -390.560052 90)
		(property "Reference" "C354"
			(at 0 0 90)
			(layer "B.SilkS")
			(hide yes)
			(effects
				(font
					(size 1.27 1.27)
				)
				(justify mirror)
			)
		)
		(property "Value" ""
			(at 0 0 90)
			(layer "B.Fab")
			(effects
				(font
					(size 1.27 1.27)
				)
				(justify mirror)
			)
		)
		(duplicate_pad_numbers_are_jumpers no)
		(fp_line
			(start 0.7874 -0.4064)
			(end -0.7874 -0.4064)
			(stroke
				(width 0.1524)
				(type default)
			)
			(layer "B.SilkS")
		)
		(fp_line
			(start -0.7874 -0.4064)
			(end -0.7874 0.4064)
			(stroke
				(width 0.1524)
				(type default)
			)
			(layer "B.SilkS")
		)
		(fp_line
			(start 0.7874 0.4064)
			(end 0.7874 -0.4064)
			(stroke
				(width 0.1524)
				(type default)
			)
			(layer "B.SilkS")
		)
		(fp_line
			(start -0.7874 0.4064)
			(end 0.7874 0.4064)
			(stroke
				(width 0.1524)
				(type default)
			)
			(layer "B.SilkS")
		)
		(fp_line
			(start 0.67945 -0.305054)
			(end 0.12065 -0.305054)
			(stroke
				(width 0.1)
				(type default)
			)
			(layer "B.Fab")
		)
		(fp_line
			(start 0.12065 -0.305054)
			(end 0.12065 -0.2794)
			(stroke
				(width 0.1)
				(type default)
			)
			(layer "B.Fab")
		)
		(fp_line
			(start -0.12065 -0.3048)
			(end -0.67945 -0.3048)
			(stroke
				(width 0.1)
				(type default)
			)
			(layer "B.Fab")
		)
		(fp_line
			(start -0.67945 -0.3048)
			(end -0.67945 0.3048)
			(stroke
				(width 0.1)
				(type default)
			)
			(layer "B.Fab")
		)
		(fp_line
			(start 0.12065 -0.2794)
			(end -0.12065 -0.2794)
			(stroke
				(width 0.1)
				(type default)
			)
			(layer "B.Fab")
		)
		(fp_line
			(start -0.12065 -0.2794)
			(end -0.12065 -0.3048)
			(stroke
				(width 0.1)
				(type default)
			)
			(layer "B.Fab")
		)
		(fp_line
			(start 0.12065 0.2794)
			(end 0.12065 0.3048)
			(stroke
				(width 0.1)
				(type default)
			)
			(layer "B.Fab")
		)
		(fp_line
			(start -0.120396 0.2794)
			(end 0.12065 0.2794)
			(stroke
				(width 0.1)
				(type default)
			)
			(layer "B.Fab")
		)
		(fp_line
			(start 0.67945 0.3048)
			(end 0.67945 -0.305054)
			(stroke
				(width 0.1)
				(type default)
			)
			(layer "B.Fab")
		)
		(fp_line
			(start 0.12065 0.3048)
			(end 0.67945 0.3048)
			(stroke
				(width 0.1)
				(type default)
			)
			(layer "B.Fab")
		)
		(fp_line
			(start -0.120396 0.3048)
			(end -0.120396 0.2794)
			(stroke
				(width 0.1)
				(type default)
			)
			(layer "B.Fab")
		)
		(fp_line
			(start -0.67945 0.3048)
			(end -0.120396 0.3048)
			(stroke
				(width 0.1)
				(type default)
			)
			(layer "B.Fab")
		)
		(pad "1" smd circle
			(at 0.40005 0 270)
			(size 0 0)
			(layers "B.Cu" "B.Mask" "B.Paste")
			(net "P0V9_CPU1_RT1_2A")
		)
		(pad "2" smd circle
			(at -0.40005 0 270)
			(size 0 0)
			(layers "B.Cu" "B.Mask" "B.Paste")
			(net "GND")
		)
	)
	(footprint ""
		(layer "B.Cu")
		(at 322.878958 -196.678296)
		(property "Reference" "R410"
			(at 0 0 0)
			(layer "B.SilkS")
			(hide yes)
			(effects
				(font
					(size 1.27 1.27)
				)
				(justify mirror)
			)
		)
		(property "Value" ""
			(at 0 0 0)
			(layer "B.Fab")
			(effects
				(font
					(size 1.27 1.27)
				)
				(justify mirror)
			)
		)
		(duplicate_pad_numbers_are_jumpers no)
		(fp_line
			(start -0.7874 -0.4064)
			(end -0.7874 0.4064)
			(stroke
				(width 0.1524)
				(type default)
			)
			(layer "B.SilkS")
		)
		(fp_line
			(start -0.7874 0.4064)
			(end 0.7874 0.4064)
			(stroke
				(width 0.1524)
				(type default)
			)
			(layer "B.SilkS")
		)
		(fp_line
			(start 0.7874 -0.4064)
			(end -0.7874 -0.4064)
			(stroke
				(width 0.1524)
				(type default)
			)
			(layer "B.SilkS")
		)
		(fp_line
			(start 0.7874 0.4064)
			(end 0.7874 -0.4064)
			(stroke
				(width 0.1524)
				(type default)
			)
			(layer "B.SilkS")
		)
		(fp_line
			(start -0.67945 -0.3048)
			(end -0.67945 0.3048)
			(stroke
				(width 0.1)
				(type default)
			)
			(layer "B.Fab")
		)
		(fp_line
			(start -0.67945 0.3048)
			(end -0.120396 0.3048)
			(stroke
				(width 0.1)
				(type default)
			)
			(layer "B.Fab")
		)
		(fp_line
			(start -0.12065 -0.3048)
			(end -0.67945 -0.3048)
			(stroke
				(width 0.1)
				(type default)
			)
			(layer "B.Fab")
		)
		(fp_line
			(start -0.12065 -0.2794)
			(end -0.12065 -0.3048)
			(stroke
				(width 0.1)
				(type default)
			)
			(layer "B.Fab")
		)
		(fp_line
			(start -0.120396 0.2794)
			(end 0.12065 0.2794)
			(stroke
				(width 0.1)
				(type default)
			)
			(layer "B.Fab")
		)
		(fp_line
			(start -0.120396 0.3048)
			(end -0.120396 0.2794)
			(stroke
				(width 0.1)
				(type default)
			)
			(layer "B.Fab")
		)
		(fp_line
			(start 0.12065 -0.305054)
			(end 0.12065 -0.2794)
			(stroke
				(width 0.1)
				(type default)
			)
			(layer "B.Fab")
		)
		(fp_line
			(start 0.12065 -0.2794)
			(end -0.12065 -0.2794)
			(stroke
				(width 0.1)
				(type default)
			)
			(layer "B.Fab")
		)
		(fp_line
			(start 0.12065 0.2794)
			(end 0.12065 0.3048)
			(stroke
				(width 0.1)
				(type default)
			)
			(layer "B.Fab")
		)
		(fp_line
			(start 0.12065 0.3048)
			(end 0.67945 0.3048)
			(stroke
				(width 0.1)
				(type default)
			)
			(layer "B.Fab")
		)
		(fp_line
			(start 0.67945 -0.305054)
			(end 0.12065 -0.305054)
			(stroke
				(width 0.1)
				(type default)
			)
			(layer "B.Fab")
		)
		(fp_line
			(start 0.67945 0.3048)
			(end 0.67945 -0.305054)
			(stroke
				(width 0.1)
				(type default)
			)
			(layer "B.Fab")
		)
		(pad "1" smd circle
			(at 0.40005 0 180)
			(size 0 0)
			(layers "B.Cu" "B.Mask" "B.Paste")
			(net "CPU0_BP2")
		)
		(pad "2" smd circle
			(at -0.40005 0 180)
			(size 0 0)
			(layers "B.Cu" "B.Mask" "B.Paste")
			(net "PVDD18_S5_P0")
		)
	)
	(footprint ""
		(layer "B.Cu")
		(at 404.070058 -319.748916 -90)
		(property "Reference" "R430"
			(at 0 0 90)
			(layer "B.SilkS")
			(hide yes)
			(effects
				(font
					(size 1.27 1.27)
				)
				(justify mirror)
			)
		)
		(property "Value" ""
			(at 0 0 90)
			(layer "B.Fab")
			(effects
				(font
					(size 1.27 1.27)
				)
				(justify mirror)
			)
		)
		(duplicate_pad_numbers_are_jumpers no)
		(fp_line
			(start -0.7874 0.4064)
			(end 0.7874 0.4064)
			(stroke
				(width 0.1524)
				(type default)
			)
			(layer "B.SilkS")
		)
		(fp_line
			(start 0.7874 0.4064)
			(end 0.7874 -0.4064)
			(stroke
				(width 0.1524)
				(type default)
			)
			(layer "B.SilkS")
		)
		(fp_line
			(start -0.7874 -0.4064)
			(end -0.7874 0.4064)
			(stroke
				(width 0.1524)
				(type default)
			)
			(layer "B.SilkS")
		)
		(fp_line
			(start 0.7874 -0.4064)
			(end -0.7874 -0.4064)
			(stroke
				(width 0.1524)
				(type default)
			)
			(layer "B.SilkS")
		)
		(fp_line
			(start -0.67945 0.3048)
			(end -0.120396 0.3048)
			(stroke
				(width 0.1)
				(type default)
			)
			(layer "B.Fab")
		)
		(fp_line
			(start -0.120396 0.3048)
			(end -0.120396 0.2794)
			(stroke
				(width 0.1)
				(type default)
			)
			(layer "B.Fab")
		)
		(fp_line
			(start 0.12065 0.3048)
			(end 0.67945 0.3048)
			(stroke
				(width 0.1)
				(type default)
			)
			(layer "B.Fab")
		)
		(fp_line
			(start 0.67945 0.3048)
			(end 0.67945 -0.305054)
			(stroke
				(width 0.1)
				(type default)
			)
			(layer "B.Fab")
		)
		(fp_line
			(start -0.120396 0.2794)
			(end 0.12065 0.2794)
			(stroke
				(width 0.1)
				(type default)
			)
			(layer "B.Fab")
		)
		(fp_line
			(start 0.12065 0.2794)
			(end 0.12065 0.3048)
			(stroke
				(width 0.1)
				(type default)
			)
			(layer "B.Fab")
		)
		(fp_line
			(start -0.12065 -0.2794)
			(end -0.12065 -0.3048)
			(stroke
				(width 0.1)
				(type default)
			)
			(layer "B.Fab")
		)
		(fp_line
			(start 0.12065 -0.2794)
			(end -0.12065 -0.2794)
			(stroke
				(width 0.1)
				(type default)
			)
			(layer "B.Fab")
		)
		(fp_line
			(start -0.67945 -0.3048)
			(end -0.67945 0.3048)
			(stroke
				(width 0.1)
				(type default)
			)
			(layer "B.Fab")
		)
		(fp_line
			(start -0.12065 -0.3048)
			(end -0.67945 -0.3048)
			(stroke
				(width 0.1)
				(type default)
			)
			(layer "B.Fab")
		)
		(fp_line
			(start 0.12065 -0.305054)
			(end 0.12065 -0.2794)
			(stroke
				(width 0.1)
				(type default)
			)
			(layer "B.Fab")
		)
		(fp_line
			(start 0.67945 -0.305054)
			(end 0.12065 -0.305054)
			(stroke
				(width 0.1)
				(type default)
			)
			(layer "B.Fab")
		)
		(pad "1" smd circle
			(at 0.40005 0 90)
			(size 0 0)
			(layers "B.Cu" "B.Mask" "B.Paste")
			(net "SMB_CPU0_4_R_SCL")
		)
		(pad "2" smd circle
			(at -0.40005 0 90)
			(size 0 0)
			(layers "B.Cu" "B.Mask" "B.Paste")
			(net "SMB_CPU0_4_SCL")
		)
	)
	(footprint ""
		(layer "B.Cu")
		(at 397.788892 -202.324208)
		(property "Reference" "R454"
			(at 0 0 0)
			(layer "B.SilkS")
			(hide yes)
			(effects
				(font
					(size 1.27 1.27)
				)
				(justify mirror)
			)
		)
		(property "Value" ""
			(at 0 0 0)
			(layer "B.Fab")
			(effects
				(font
					(size 1.27 1.27)
				)
				(justify mirror)
			)
		)
		(duplicate_pad_numbers_are_jumpers no)
		(fp_line
			(start -0.7874 -0.4064)
			(end -0.7874 0.4064)
			(stroke
				(width 0.1524)
				(type default)
			)
			(layer "B.SilkS")
		)
		(fp_line
			(start -0.7874 0.4064)
			(end 0.7874 0.4064)
			(stroke
				(width 0.1524)
				(type default)
			)
			(layer "B.SilkS")
		)
		(fp_line
			(start 0.7874 -0.4064)
			(end -0.7874 -0.4064)
			(stroke
				(width 0.1524)
				(type default)
			)
			(layer "B.SilkS")
		)
		(fp_line
			(start 0.7874 0.4064)
			(end 0.7874 -0.4064)
			(stroke
				(width 0.1524)
				(type default)
			)
			(layer "B.SilkS")
		)
		(fp_line
			(start -0.67945 -0.3048)
			(end -0.67945 0.3048)
			(stroke
				(width 0.1)
				(type default)
			)
			(layer "B.Fab")
		)
		(fp_line
			(start -0.67945 0.3048)
			(end -0.120396 0.3048)
			(stroke
				(width 0.1)
				(type default)
			)
			(layer "B.Fab")
		)
		(fp_line
			(start -0.12065 -0.3048)
			(end -0.67945 -0.3048)
			(stroke
				(width 0.1)
				(type default)
			)
			(layer "B.Fab")
		)
		(fp_line
			(start -0.12065 -0.2794)
			(end -0.12065 -0.3048)
			(stroke
				(width 0.1)
				(type default)
			)
			(layer "B.Fab")
		)
		(fp_line
			(start -0.120396 0.2794)
			(end 0.12065 0.2794)
			(stroke
				(width 0.1)
				(type default)
			)
			(layer "B.Fab")
		)
		(fp_line
			(start -0.120396 0.3048)
			(end -0.120396 0.2794)
			(stroke
				(width 0.1)
				(type default)
			)
			(layer "B.Fab")
		)
		(fp_line
			(start 0.12065 -0.305054)
			(end 0.12065 -0.2794)
			(stroke
				(width 0.1)
				(type default)
			)
			(layer "B.Fab")
		)
		(fp_line
			(start 0.12065 -0.2794)
			(end -0.12065 -0.2794)
			(stroke
				(width 0.1)
				(type default)
			)
			(layer "B.Fab")
		)
		(fp_line
			(start 0.12065 0.2794)
			(end 0.12065 0.3048)
			(stroke
				(width 0.1)
				(type default)
			)
			(layer "B.Fab")
		)
		(fp_line
			(start 0.12065 0.3048)
			(end 0.67945 0.3048)
			(stroke
				(width 0.1)
				(type default)
			)
			(layer "B.Fab")
		)
		(fp_line
			(start 0.67945 -0.305054)
			(end 0.12065 -0.305054)
			(stroke
				(width 0.1)
				(type default)
			)
			(layer "B.Fab")
		)
		(fp_line
			(start 0.67945 0.3048)
			(end 0.67945 -0.305054)
			(stroke
				(width 0.1)
				(type default)
			)
			(layer "B.Fab")
		)
		(pad "1" smd circle
			(at 0.40005 0 180)
			(size 0 0)
			(layers "B.Cu" "B.Mask" "B.Paste")
			(net "PVDD18_S5_P0")
		)
		(pad "2" smd circle
			(at -0.40005 0 180)
			(size 0 0)
			(layers "B.Cu" "B.Mask" "B.Paste")
			(net "SCM_USB_OC_BUF_N")
		)
	)
	(footprint ""
		(layer "B.Cu")
		(at 46.359318 -430.165002 90)
		(property "Reference" "R3474"
			(at 0 0 90)
			(layer "B.SilkS")
			(hide yes)
			(effects
				(font
					(size 1.27 1.27)
				)
				(justify mirror)
			)
		)
		(property "Value" ""
			(at 0 0 90)
			(layer "B.Fab")
			(effects
				(font
					(size 1.27 1.27)
				)
				(justify mirror)
			)
		)
		(duplicate_pad_numbers_are_jumpers no)
		(fp_line
			(start 0.7874 -0.4064)
			(end -0.7874 -0.4064)
			(stroke
				(width 0.1524)
				(type default)
			)
			(layer "B.SilkS")
		)
		(fp_line
			(start -0.7874 -0.4064)
			(end -0.7874 0.4064)
			(stroke
				(width 0.1524)
				(type default)
			)
			(layer "B.SilkS")
		)
		(fp_line
			(start 0.7874 0.4064)
			(end 0.7874 -0.4064)
			(stroke
				(width 0.1524)
				(type default)
			)
			(layer "B.SilkS")
		)
		(fp_line
			(start -0.7874 0.4064)
			(end 0.7874 0.4064)
			(stroke
				(width 0.1524)
				(type default)
			)
			(layer "B.SilkS")
		)
		(fp_line
			(start 0.67945 -0.305054)
			(end 0.12065 -0.305054)
			(stroke
				(width 0.1)
				(type default)
			)
			(layer "B.Fab")
		)
		(fp_line
			(start 0.12065 -0.305054)
			(end 0.12065 -0.2794)
			(stroke
				(width 0.1)
				(type default)
			)
			(layer "B.Fab")
		)
		(fp_line
			(start -0.12065 -0.3048)
			(end -0.67945 -0.3048)
			(stroke
				(width 0.1)
				(type default)
			)
			(layer "B.Fab")
		)
		(fp_line
			(start -0.67945 -0.3048)
			(end -0.67945 0.3048)
			(stroke
				(width 0.1)
				(type default)
			)
			(layer "B.Fab")
		)
		(fp_line
			(start 0.12065 -0.2794)
			(end -0.12065 -0.2794)
			(stroke
				(width 0.1)
				(type default)
			)
			(layer "B.Fab")
		)
		(fp_line
			(start -0.12065 -0.2794)
			(end -0.12065 -0.3048)
			(stroke
				(width 0.1)
				(type default)
			)
			(layer "B.Fab")
		)
		(fp_line
			(start 0.12065 0.2794)
			(end 0.12065 0.3048)
			(stroke
				(width 0.1)
				(type default)
			)
			(layer "B.Fab")
		)
		(fp_line
			(start -0.120396 0.2794)
			(end 0.12065 0.2794)
			(stroke
				(width 0.1)
				(type default)
			)
			(layer "B.Fab")
		)
		(fp_line
			(start 0.67945 0.3048)
			(end 0.67945 -0.305054)
			(stroke
				(width 0.1)
				(type default)
			)
			(layer "B.Fab")
		)
		(fp_line
			(start 0.12065 0.3048)
			(end 0.67945 0.3048)
			(stroke
				(width 0.1)
				(type default)
			)
			(layer "B.Fab")
		)
		(fp_line
			(start -0.120396 0.3048)
			(end -0.120396 0.2794)
			(stroke
				(width 0.1)
				(type default)
			)
			(layer "B.Fab")
		)
		(fp_line
			(start -0.67945 0.3048)
			(end -0.120396 0.3048)
			(stroke
				(width 0.1)
				(type default)
			)
			(layer "B.Fab")
		)
		(pad "1" smd circle
			(at 0.40005 0 270)
			(size 0 0)
			(layers "B.Cu" "B.Mask" "B.Paste")
			(net "P3V3_AUX")
		)
		(pad "2" smd circle
			(at -0.40005 0 270)
			(size 0 0)
			(layers "B.Cu" "B.Mask" "B.Paste")
			(net "GPU_PRSNT")
		)
	)
	(footprint ""
		(layer "B.Cu")
		(at 151.884634 -316.353952 90)
		(property "Reference" "C238"
			(at 0 0 90)
			(layer "B.SilkS")
			(hide yes)
			(effects
				(font
					(size 1.27 1.27)
				)
				(justify mirror)
			)
		)
		(property "Value" ""
			(at 0 0 90)
			(layer "B.Fab")
			(effects
				(font
					(size 1.27 1.27)
				)
				(justify mirror)
			)
		)
		(duplicate_pad_numbers_are_jumpers no)
		(fp_line
			(start 0.7874 -0.4064)
			(end -0.7874 -0.4064)
			(stroke
				(width 0.1524)
				(type default)
			)
			(layer "B.SilkS")
		)
		(fp_line
			(start -0.7874 -0.4064)
			(end -0.7874 0.4064)
			(stroke
				(width 0.1524)
				(type default)
			)
			(layer "B.SilkS")
		)
		(fp_line
			(start 0.7874 0.4064)
			(end 0.7874 -0.4064)
			(stroke
				(width 0.1524)
				(type default)
			)
			(layer "B.SilkS")
		)
		(fp_line
			(start -0.7874 0.4064)
			(end 0.7874 0.4064)
			(stroke
				(width 0.1524)
				(type default)
			)
			(layer "B.SilkS")
		)
		(fp_line
			(start 0.67945 -0.305054)
			(end 0.12065 -0.305054)
			(stroke
				(width 0.1)
				(type default)
			)
			(layer "B.Fab")
		)
		(fp_line
			(start 0.12065 -0.305054)
			(end 0.12065 -0.2794)
			(stroke
				(width 0.1)
				(type default)
			)
			(layer "B.Fab")
		)
		(fp_line
			(start -0.12065 -0.3048)
			(end -0.67945 -0.3048)
			(stroke
				(width 0.1)
				(type default)
			)
			(layer "B.Fab")
		)
		(fp_line
			(start -0.67945 -0.3048)
			(end -0.67945 0.3048)
			(stroke
				(width 0.1)
				(type default)
			)
			(layer "B.Fab")
		)
		(fp_line
			(start 0.12065 -0.2794)
			(end -0.12065 -0.2794)
			(stroke
				(width 0.1)
				(type default)
			)
			(layer "B.Fab")
		)
		(fp_line
			(start -0.12065 -0.2794)
			(end -0.12065 -0.3048)
			(stroke
				(width 0.1)
				(type default)
			)
			(layer "B.Fab")
		)
		(fp_line
			(start 0.12065 0.2794)
			(end 0.12065 0.3048)
			(stroke
				(width 0.1)
				(type default)
			)
			(layer "B.Fab")
		)
		(fp_line
			(start -0.120396 0.2794)
			(end 0.12065 0.2794)
			(stroke
				(width 0.1)
				(type default)
			)
			(layer "B.Fab")
		)
		(fp_line
			(start 0.67945 0.3048)
			(end 0.67945 -0.305054)
			(stroke
				(width 0.1)
				(type default)
			)
			(layer "B.Fab")
		)
		(fp_line
			(start 0.12065 0.3048)
			(end 0.67945 0.3048)
			(stroke
				(width 0.1)
				(type default)
			)
			(layer "B.Fab")
		)
		(fp_line
			(start -0.120396 0.3048)
			(end -0.120396 0.2794)
			(stroke
				(width 0.1)
				(type default)
			)
			(layer "B.Fab")
		)
		(fp_line
			(start -0.67945 0.3048)
			(end -0.120396 0.3048)
			(stroke
				(width 0.1)
				(type default)
			)
			(layer "B.Fab")
		)
		(pad "1" smd circle
			(at 0.40005 0 270)
			(size 0 0)
			(layers "B.Cu" "B.Mask" "B.Paste")
			(net "XTAL_CPU1_R_X32K_X1")
		)
		(pad "2" smd circle
			(at -0.40005 0 270)
			(size 0 0)
			(layers "B.Cu" "B.Mask" "B.Paste")
			(net "GND")
		)
	)
)
